# T6G (Grand Teton) — schematic netlist excerpt (pin names and nets, part order shuffled) for the footprints in the layout excerpt that follows; sources: Cadence DE-HDL packaged netlist, KiCad conversion of 04192023_DAF0TMB3IC0_F0TG_MB_C_brd_V02_OCP.brd

C2513  Q_CAP  22UF 4V 20% X6S  pkg C0402  page 71 : A = PVDD18_S5_P0 ; B = GND
C1073  Q_CAP  0.1UF 10V 10% X7S  pkg C0201  page 186 : A = P3V3_AUX ; B = GND
C132  Q_CAP  0.1UF 25V 10% X7R  pkg 0402  page 97 : A = P3V3_AUX ; B = GND

(kicad_pcb
	(version 20260206)
	(generator "pcbnew")
	(generator_version "10.0")
	(general
		(thickness 1.6)
		(legacy_teardrops no)
	)
	(paper "A4")
	(title_block
		(title "04192023_DAF0TMB3IC0_F0TG_MB_C_brd_V02_OCP.brd")
		(comment 1 "Grand Teton / footprints 5607-5609 of 8354")
	)
	(layers
		(0 "F.Cu" signal "TOP")
		(4 "In1.Cu" signal "GND")
		(6 "In2.Cu" signal "IN1")
		(8 "In3.Cu" signal "GND1")
		(10 "In4.Cu" signal "IN2")
		(12 "In5.Cu" signal "GND2")
		(14 "In6.Cu" signal "IN3")
		(16 "In7.Cu" signal "GND3")
		(18 "In8.Cu" signal "VCC")
		(20 "In9.Cu" signal "VCC1")
		(22 "In10.Cu" signal "GND4")
		(24 "In11.Cu" signal "IN4")
		(26 "In12.Cu" signal "GND5")
		(28 "In13.Cu" signal "IN5")
		(30 "In14.Cu" signal "GND6")
		(32 "In15.Cu" signal "IN6")
		(34 "In16.Cu" signal "GND7")
		(2 "B.Cu" signal "BOTTOM")
		(9 "F.Adhes" user "F.Adhesive")
		(11 "B.Adhes" user "B.Adhesive")
		(13 "F.Paste" user "Package Geometry/Pastemask Top")
		(15 "B.Paste" user "Package Geometry/Pastemask Bottom")
		(5 "F.SilkS" user "Ref Des/Silkscreen Top")
		(7 "B.SilkS" user "Ref Des/Silkscreen Bottom")
		(1 "F.Mask" user "Board Geometry/Soldermask Top")
		(3 "B.Mask" user "Board Geometry/Soldermask Bottom")
		(17 "Dwgs.User" user "User.Drawings")
		(19 "Cmts.User" user "User.Comments")
		(21 "Eco1.User" user "User.Eco1")
		(23 "Eco2.User" user "User.Eco2")
		(25 "Edge.Cuts" user "Board Geometry/Outline")
		(27 "Margin" user)
		(31 "F.CrtYd" user "Package Geometry/Place Bound Top")
		(29 "B.CrtYd" user "Package Geometry/Place Bound Bottom")
		(35 "F.Fab" user "Ref Des/Assembly Top")
		(33 "B.Fab" user "Ref Des/Assembly Bottom")
	)
	(footprint ""
		(layer "B.Cu")
		(at 347.008958 -249.36831 180)
		(property "Reference" "C2513"
			(at 0 0 0)
			(layer "B.SilkS")
			(hide yes)
			(effects
				(font
					(size 1.27 1.27)
				)
				(justify mirror)
			)
		)
		(property "Value" ""
			(at 0 0 0)
			(layer "B.Fab")
			(effects
				(font
					(size 1.27 1.27)
				)
				(justify mirror)
			)
		)
		(duplicate_pad_numbers_are_jumpers no)
		(fp_line
			(start 0.7874 0.4064)
			(end 0.7874 -0.4064)
			(stroke
				(width 0.1524)
				(type default)
			)
			(layer "B.SilkS")
		)
		(fp_line
			(start 0.7874 -0.4064)
			(end -0.7874 -0.4064)
			(stroke
				(width 0.1524)
				(type default)
			)
			(layer "B.SilkS")
		)
		(fp_line
			(start -0.7874 0.4064)
			(end 0.7874 0.4064)
			(stroke
				(width 0.1524)
				(type default)
			)
			(layer "B.SilkS")
		)
		(fp_line
			(start -0.7874 -0.4064)
			(end -0.7874 0.4064)
			(stroke
				(width 0.1524)
				(type default)
			)
			(layer "B.SilkS")
		)
		(fp_line
			(start 0.67945 0.3048)
			(end 0.67945 -0.305054)
			(stroke
				(width 0.1)
				(type default)
			)
			(layer "B.Fab")
		)
		(fp_line
			(start 0.67945 -0.305054)
			(end 0.12065 -0.305054)
			(stroke
				(width 0.1)
				(type default)
			)
			(layer "B.Fab")
		)
		(fp_line
			(start 0.12065 0.3048)
			(end 0.67945 0.3048)
			(stroke
				(width 0.1)
				(type default)
			)
			(layer "B.Fab")
		)
		(fp_line
			(start 0.12065 0.2794)
			(end 0.12065 0.3048)
			(stroke
				(width 0.1)
				(type default)
			)
			(layer "B.Fab")
		)
		(fp_line
			(start 0.12065 -0.2794)
			(end -0.12065 -0.2794)
			(stroke
				(width 0.1)
				(type default)
			)
			(layer "B.Fab")
		)
		(fp_line
			(start 0.12065 -0.305054)
			(end 0.12065 -0.2794)
			(stroke
				(width 0.1)
				(type default)
			)
			(layer "B.Fab")
		)
		(fp_line
			(start -0.120396 0.3048)
			(end -0.120396 0.2794)
			(stroke
				(width 0.1)
				(type default)
			)
			(layer "B.Fab")
		)
		(fp_line
			(start -0.120396 0.2794)
			(end 0.12065 0.2794)
			(stroke
				(width 0.1)
				(type default)
			)
			(layer "B.Fab")
		)
		(fp_line
			(start -0.12065 -0.2794)
			(end -0.12065 -0.3048)
			(stroke
				(width 0.1)
				(type default)
			)
			(layer "B.Fab")
		)
		(fp_line
			(start -0.12065 -0.3048)
			(end -0.67945 -0.3048)
			(stroke
				(width 0.1)
				(type default)
			)
			(layer "B.Fab")
		)
		(fp_line
			(start -0.67945 0.3048)
			(end -0.120396 0.3048)
			(stroke
				(width 0.1)
				(type default)
			)
			(layer "B.Fab")
		)
		(fp_line
			(start -0.67945 -0.3048)
			(end -0.67945 0.3048)
			(stroke
				(width 0.1)
				(type default)
			)
			(layer "B.Fab")
		)
		(pad "1" smd circle
			(at 0.40005 0)
			(size 0 0)
			(layers "B.Cu" "B.Mask" "B.Paste")
			(net "PVDD18_S5_P0")
		)
		(pad "2" smd circle
			(at -0.40005 0)
			(size 0 0)
			(layers "B.Cu" "B.Mask" "B.Paste")
			(net "GND")
		)
	)
	(footprint ""
		(layer "B.Cu")
		(at 298.901104 -427.261528 180)
		(property "Reference" "C1073"
			(at 0 0 0)
			(layer "B.SilkS")
			(hide yes)
			(effects
				(font
					(size 1.27 1.27)
				)
				(justify mirror)
			)
		)
		(property "Value" ""
			(at 0 0 0)
			(layer "B.Fab")
			(effects
				(font
					(size 1.27 1.27)
				)
				(justify mirror)
			)
		)
		(duplicate_pad_numbers_are_jumpers no)
		(fp_line
			(start 0.299974 0.150114)
			(end 0.299974 -0.150114)
			(stroke
				(width 0.1)
				(type default)
			)
			(layer "B.Fab")
		)
		(fp_line
			(start 0.299974 -0.150114)
			(end -0.299974 -0.150114)
			(stroke
				(width 0.1)
				(type default)
			)
			(layer "B.Fab")
		)
		(fp_line
			(start -0.299974 0.150114)
			(end 0.299974 0.150114)
			(stroke
				(width 0.1)
				(type default)
			)
			(layer "B.Fab")
		)
		(fp_line
			(start -0.299974 -0.150114)
			(end -0.299974 0.150114)
			(stroke
				(width 0.1)
				(type default)
			)
			(layer "B.Fab")
		)
		(pad "1" smd rect
			(at 0.2667 0)
			(size 0.3048 0.381)
			(layers "B.Cu" "B.Mask" "B.Paste")
			(net "P3V3_AUX")
		)
		(pad "2" smd rect
			(at -0.2667 0)
			(size 0.3048 0.381)
			(layers "B.Cu" "B.Mask" "B.Paste")
			(net "GND")
		)
	)
	(footprint ""
		(layer "B.Cu")
		(at 445.888618 -193.99631)
		(property "Reference" "C132"
			(at 0 0 0)
			(layer "B.SilkS")
			(hide yes)
			(effects
				(font
					(size 1.27 1.27)
				)
				(justify mirror)
			)
		)
		(property "Value" ""
			(at 0 0 0)
			(layer "B.Fab")
			(effects
				(font
					(size 1.27 1.27)
				)
				(justify mirror)
			)
		)
		(duplicate_pad_numbers_are_jumpers no)
		(fp_line
			(start -0.7874 -0.4064)
			(end -0.7874 0.4064)
			(stroke
				(width 0.1524)
				(type default)
			)
			(layer "B.SilkS")
		)
		(fp_line
			(start -0.7874 0.4064)
			(end 0.7874 0.4064)
			(stroke
				(width 0.1524)
				(type default)
			)
			(layer "B.SilkS")
		)
		(fp_line
			(start 0.7874 -0.4064)
			(end -0.7874 -0.4064)
			(stroke
				(width 0.1524)
				(type default)
			)
			(layer "B.SilkS")
		)
		(fp_line
			(start 0.7874 0.4064)
			(end 0.7874 -0.4064)
			(stroke
				(width 0.1524)
				(type default)
			)
			(layer "B.SilkS")
		)
		(fp_line
			(start -0.67945 -0.3048)
			(end -0.67945 0.3048)
			(stroke
				(width 0.1)
				(type default)
			)
			(layer "B.Fab")
		)
		(fp_line
			(start -0.67945 0.3048)
			(end -0.120396 0.3048)
			(stroke
				(width 0.1)
				(type default)
			)
			(layer "B.Fab")
		)
		(fp_line
			(start -0.12065 -0.3048)
			(end -0.67945 -0.3048)
			(stroke
				(width 0.1)
				(type default)
			)
			(layer "B.Fab")
		)
		(fp_line
			(start -0.12065 -0.2794)
			(end -0.12065 -0.3048)
			(stroke
				(width 0.1)
				(type default)
			)
			(layer "B.Fab")
		)
		(fp_line
			(start -0.120396 0.2794)
			(end 0.12065 0.2794)
			(stroke
				(width 0.1)
				(type default)
			)
			(layer "B.Fab")
		)
		(fp_line
			(start -0.120396 0.3048)
			(end -0.120396 0.2794)
			(stroke
				(width 0.1)
				(type default)
			)
			(layer "B.Fab")
		)
		(fp_line
			(start 0.12065 -0.305054)
			(end 0.12065 -0.2794)
			(stroke
				(width 0.1)
				(type default)
			)
			(layer "B.Fab")
		)
		(fp_line
			(start 0.12065 -0.2794)
			(end -0.12065 -0.2794)
			(stroke
				(width 0.1)
				(type default)
			)
			(layer "B.Fab")
		)
		(fp_line
			(start 0.12065 0.2794)
			(end 0.12065 0.3048)
			(stroke
				(width 0.1)
				(type default)
			)
			(layer "B.Fab")
		)
		(fp_line
			(start 0.12065 0.3048)
			(end 0.67945 0.3048)
			(stroke
				(width 0.1)
				(type default)
			)
			(layer "B.Fab")
		)
		(fp_line
			(start 0.67945 -0.305054)
			(end 0.12065 -0.305054)
			(stroke
				(width 0.1)
				(type default)
			)
			(layer "B.Fab")
		)
		(fp_line
			(start 0.67945 0.3048)
			(end 0.67945 -0.305054)
			(stroke
				(width 0.1)
				(type default)
			)
			(layer "B.Fab")
		)
		(pad "1" smd circle
			(at 0.40005 0 180)
			(size 0 0)
			(layers "B.Cu" "B.Mask" "B.Paste")
			(net "P3V3_AUX")
		)
		(pad "2" smd circle
			(at -0.40005 0 180)
			(size 0 0)
			(layers "B.Cu" "B.Mask" "B.Paste")
			(net "GND")
		)
	)
)
